FILE_TYPE = MULTI_PHYS_TABLE;

PART 'CONN_HDR_2X4_F_S_SMT'
CLASS=IO

{========================================================================================}
:CLS_PN             = JEDEC_TYPE              | ALT_SYMBOLS               | DESCRIPTION                                                 | CPN_STATUS ;
{========================================================================================}
 'G200-11010-01'    = 'S_F_H_2X4_NP2_S_P0197' | '(S_F_H_2X4_NP2_S_P0197)' | 'CON,RECEPT,2X4,8PIN,3.5MM STACKING HEIGHT,0.5MM PITCH,SMT' | ''        
 'G200-11216-01'    = 'S_F_H_2X4_S_P100'      | '(S_F_H_2X4_S_P100)'      | 'CON,RECEPT,2X4,8PIN,2.54MM PITCH,SMT'                      | ''        
 'G200-11819-01'    = 'S_F_H_2X4_NP2_S_P0787' | '(S_F_H_2X4_NP2_S_P0787)' | 'CON,HEADER,8P,4X2,DOUBLE VERTICAL,ALIGNMENT PIN,SMT'       | ''        
 'G200-12325-01'    = 'S_F_H_2X4_S_P0787'     | '(S_F_H_2X4_S_P0787)'     | 'CON, 2MM PITCH,8P,4X2,10U,LOW PROFILE SOCKET,SMD'          | ''        
 'G200-13079-01'    = 'S_F_H_2X4_S_P0787_V1'  | '(S_F_H_2X4_S_P0787_V1)'  | 'CON,8P,2X4,SOCKET,2MM PITCH,VT,SMT'                        | ''        

END_PART

END.

